(kicad_pcb
	(version 20260206)
	(generator "pcbnew")
	(generator_version "10.0")
	(general
		(thickness 1.6)
		(legacy_teardrops no)
	)
	(paper "A4")
	(title_block
		(title "Bryce Canyon_F.DPB_16315-1-OCP.brd")
		(comment 1 "Bryce Canyon / footprints 1009-1015 of 2223")
	)
	(layers
		(0 "F.Cu" signal "TOP")
		(4 "In1.Cu" signal "L2GND")
		(6 "In2.Cu" signal "L3")
		(8 "In3.Cu" signal "L4GND")
		(10 "In4.Cu" signal "L5")
		(12 "In5.Cu" signal "L6VCC")
		(14 "In6.Cu" signal "L7VCC")
		(16 "In7.Cu" signal "L8")
		(18 "In8.Cu" signal "L9GND")
		(20 "In9.Cu" signal "L10")
		(22 "In10.Cu" signal "L11GND")
		(2 "B.Cu" signal "BOTTOM")
		(9 "F.Adhes" user "F.Adhesive")
		(11 "B.Adhes" user "B.Adhesive")
		(13 "F.Paste" user "Package Geometry/Pastemask Top")
		(15 "B.Paste" user "Package Geometry/Pastemask Bottom")
		(5 "F.SilkS" user "Ref Des/Silkscreen Top")
		(7 "B.SilkS" user "Ref Des/Silkscreen Bottom")
		(1 "F.Mask" user "Board Geometry/Soldermask Top")
		(3 "B.Mask" user "Board Geometry/Soldermask Bottom")
		(17 "Dwgs.User" user "User.Drawings")
		(19 "Cmts.User" user "User.Comments")
		(21 "Eco1.User" user "User.Eco1")
		(23 "Eco2.User" user "User.Eco2")
		(25 "Edge.Cuts" user "Board Geometry/Outline")
		(27 "Margin" user)
		(31 "F.CrtYd" user "Package Geometry/Place Bound Top")
		(29 "B.CrtYd" user "Package Geometry/Place Bound Bottom")
		(35 "F.Fab" user "Ref Des/Assembly Top")
		(33 "B.Fab" user "Ref Des/Assembly Bottom")
	)
	(footprint ""
		(layer "F.Cu")
		(at 463.0039 -292.016942)
		(property "Reference" "Q62"
			(at 0 0 0)
			(layer "F.SilkS")
			(hide yes)
			(effects
				(font
					(size 1.27 1.27)
				)
			)
		)
		(property "Value" "AO4407AL-GP"
			(at -3.707384 -1.5367 0)
			(unlocked yes)
			(layer "F.Fab")
			(hide yes)
			(effects
				(font
					(size 1.016 1.016)
					(thickness 0.1524)
				)
			)
		)
		(property "Device Type" "SOIC8H69"
			(at -3.707384 -3.0607 0)
			(unlocked yes)
			(layer "F.Fab")
			(hide yes)
			(effects
				(font
					(size 1.016 1.016)
					(thickness 0.1524)
				)
			)
		)
		(duplicate_pad_numbers_are_jumpers no)
		(fp_line
			(start -2.7432 -1.4224)
			(end -2.7432 1.4224)
			(stroke
				(width 0.1524)
				(type default)
			)
			(layer "F.SilkS")
		)
		(fp_line
			(start -2.7432 1.4224)
			(end -2.6416 1.4224)
			(stroke
				(width 0.1524)
				(type default)
			)
			(layer "F.SilkS")
		)
		(fp_line
			(start -2.7432 1.4224)
			(end 2.1336 1.4224)
			(stroke
				(width 0.1524)
				(type default)
			)
			(layer "F.SilkS")
		)
		(fp_line
			(start -2.7178 -0.508)
			(end -2.1844 -0.0508)
			(stroke
				(width 0.1524)
				(type default)
			)
			(layer "F.SilkS")
		)
		(fp_line
			(start -2.6289 3.4417)
			(end -2.6289 1.4732)
			(stroke
				(width 0.381)
				(type default)
			)
			(layer "F.SilkS")
		)
		(fp_line
			(start -2.1844 -0.0508)
			(end -2.7178 0.508)
			(stroke
				(width 0.1524)
				(type default)
			)
			(layer "F.SilkS")
		)
		(fp_line
			(start 2.1336 -1.4224)
			(end -2.7432 -1.4224)
			(stroke
				(width 0.1524)
				(type default)
			)
			(layer "F.SilkS")
		)
		(fp_line
			(start 2.1336 1.4224)
			(end 2.1336 -1.4224)
			(stroke
				(width 0.1524)
				(type default)
			)
			(layer "F.SilkS")
		)
		(fp_poly
			(pts
				(xy -2.2098 -1.4224) (xy -2.2098 1.4224) (xy 2.2098 1.4224) (xy 2.2098 -1.4224)
			)
			(stroke
				(width 0)
				(type default)
			)
			(fill yes)
			(layer "F.SilkS")
		)
		(fp_rect
			(start -2.450084 2.999994)
			(end 2.450084 -2.999994)
			(stroke
				(width 0)
				(type default)
			)
			(fill no)
			(layer "F.CrtYd")
		)
		(fp_poly
			(pts
				(xy -2.8194 3.6322) (xy -2.8194 -3.6322) (xy 2.8194 -3.6322) (xy 2.8194 1.18364) (xy 2.450084 1.18364)
				(xy 2.450084 -2.999994) (xy -2.450084 -2.999994) (xy -2.450084 2.999994) (xy 2.450084 2.999994)
				(xy 2.450084 1.18618) (xy 2.8194 1.18618) (xy 2.8194 3.6322)
			)
			(stroke
				(width 0)
				(type default)
			)
			(fill no)
			(layer "F.CrtYd")
		)
		(fp_rect
			(start -2.8194 3.6322)
			(end 2.8194 -3.6322)
			(stroke
				(width 0)
				(type default)
			)
			(fill no)
			(layer "F.Fab")
		)
		(pad "1" smd rect
			(at -1.905 2.54)
			(size 0.635 1.651)
			(layers "F.Cu" "F.Mask" "F.Paste")
			(net "P12V_A")
		)
		(pad "2" smd rect
			(at -0.635 2.54)
			(size 0.635 1.651)
			(layers "F.Cu" "F.Mask" "F.Paste")
			(net "P12V_A")
		)
		(pad "3" smd rect
			(at 0.635 2.54)
			(size 0.635 1.651)
			(layers "F.Cu" "F.Mask" "F.Paste")
			(net "P12V_A")
		)
		(pad "4" smd rect
			(at 1.905 2.54)
			(size 0.635 1.651)
			(layers "F.Cu" "F.Mask" "F.Paste")
			(net "SW_HDD_N10")
		)
		(pad "5" smd rect
			(at 1.905 -2.54)
			(size 0.635 1.651)
			(layers "F.Cu" "F.Mask" "F.Paste")
			(net "P12V_HDD10")
		)
		(pad "6" smd rect
			(at 0.635 -2.54)
			(size 0.635 1.651)
			(layers "F.Cu" "F.Mask" "F.Paste")
			(net "P12V_HDD10")
		)
		(pad "7" smd rect
			(at -0.635 -2.54)
			(size 0.635 1.651)
			(layers "F.Cu" "F.Mask" "F.Paste")
			(net "P12V_HDD10")
		)
		(pad "8" smd rect
			(at -1.905 -2.54)
			(size 0.635 1.651)
			(layers "F.Cu" "F.Mask" "F.Paste")
			(net "P12V_HDD10")
		)
	)
	(footprint ""
		(layer "F.Cu")
		(at 351.208086 -62.186566 -90)
		(property "Reference" "R843"
			(at 0 0 270)
			(layer "F.SilkS")
			(hide yes)
			(effects
				(font
					(size 1.27 1.27)
				)
			)
		)
		(property "Value" "10KR2F-2-GP"
			(at 0.064008 -3.993896 270)
			(unlocked yes)
			(layer "F.Fab")
			(hide yes)
			(effects
				(font
					(size 1.016 1.016)
					(thickness 0.1524)
				)
			)
		)
		(property "Device Type" "R402H16"
			(at 0.064008 -5.517896 270)
			(unlocked yes)
			(layer "F.Fab")
			(hide yes)
			(effects
				(font
					(size 1.016 1.016)
					(thickness 0.1524)
				)
			)
		)
		(duplicate_pad_numbers_are_jumpers no)
		(fp_line
			(start -0.508 -0.9398)
			(end -0.508 0.9398)
			(stroke
				(width 0.1524)
				(type default)
			)
			(layer "F.SilkS")
		)
		(fp_line
			(start 0.508 -0.9398)
			(end -0.508 -0.9398)
			(stroke
				(width 0.1524)
				(type default)
			)
			(layer "F.SilkS")
		)
		(fp_rect
			(start -0.508 0.9398)
			(end 0.508 -0.9398)
			(stroke
				(width 0)
				(type default)
			)
			(fill no)
			(layer "F.CrtYd")
		)
		(fp_rect
			(start -0.508 0.9398)
			(end 0.508 -0.9398)
			(stroke
				(width 0)
				(type default)
			)
			(fill no)
			(layer "F.Fab")
		)
		(pad "1" smd custom
			(at 0 -0.4445 270)
			(size 0.1397 0.1397)
			(layers "F.Cu" "F.Mask" "F.Paste")
			(net "P3V3_STBY_A")
			(options
				(clearance outline)
				(anchor circle)
			)
			(primitives
				(gr_poly
					(pts
						(arc
							(start -0.1778 -0.2794)
							(mid -0.249642 -0.249642)
							(end -0.2794 -0.1778)
						)
						(arc
							(start -0.2794 0.1778)
							(mid -0.249642 0.249642)
							(end -0.1778 0.2794)
						)
						(arc
							(start 0.1778 0.2794)
							(mid 0.249642 0.249642)
							(end 0.2794 0.1778)
						)
						(arc
							(start 0.2794 -0.1778)
							(mid 0.249642 -0.249642)
							(end 0.1778 -0.2794)
						)
					)
					(width 0)
					(fill yes)
				)
			)
		)
		(pad "2" smd custom
			(at 0 0.4445 270)
			(size 0.1397 0.1397)
			(layers "F.Cu" "F.Mask" "F.Paste")
			(net "HDD_PRSNT_31")
			(options
				(clearance outline)
				(anchor circle)
			)
			(primitives
				(gr_poly
					(pts
						(arc
							(start -0.1778 -0.2794)
							(mid -0.249642 -0.249642)
							(end -0.2794 -0.1778)
						)
						(arc
							(start -0.2794 0.1778)
							(mid -0.249642 0.249642)
							(end -0.1778 0.2794)
						)
						(arc
							(start 0.1778 0.2794)
							(mid 0.249642 0.249642)
							(end 0.2794 0.1778)
						)
						(arc
							(start 0.2794 -0.1778)
							(mid 0.249642 -0.249642)
							(end 0.1778 -0.2794)
						)
					)
					(width 0)
					(fill yes)
				)
			)
		)
	)
	(footprint ""
		(layer "F.Cu")
		(at 82.006948 -64.683894 90)
		(property "Reference" "R729"
			(at 0 0 90)
			(layer "F.SilkS")
			(hide yes)
			(effects
				(font
					(size 1.27 1.27)
				)
			)
		)
		(property "Value" "2R6F-GP"
			(at -0.0508 -4.8514 90)
			(unlocked yes)
			(layer "F.Fab")
			(hide yes)
			(effects
				(font
					(size 1.016 1.016)
					(thickness 0.1524)
				)
			)
		)
		(property "Device Type" "R1206H26"
			(at 0 -6.3754 90)
			(unlocked yes)
			(layer "F.Fab")
			(hide yes)
			(effects
				(font
					(size 1.016 1.016)
					(thickness 0.1524)
				)
			)
		)
		(duplicate_pad_numbers_are_jumpers no)
		(fp_line
			(start 1.016 -2.2352)
			(end 1.016 2.2352)
			(stroke
				(width 0.1524)
				(type default)
			)
			(layer "F.SilkS")
		)
		(fp_line
			(start -1.016 -2.2352)
			(end 1.016 -2.2352)
			(stroke
				(width 0.1524)
				(type default)
			)
			(layer "F.SilkS")
		)
		(fp_line
			(start 1.016 2.2352)
			(end -1.016 2.2352)
			(stroke
				(width 0.1524)
				(type default)
			)
			(layer "F.SilkS")
		)
		(fp_line
			(start -1.016 2.2352)
			(end -1.016 -2.2352)
			(stroke
				(width 0.1524)
				(type default)
			)
			(layer "F.SilkS")
		)
		(fp_rect
			(start -1.0922 2.3114)
			(end 1.0922 -2.3114)
			(stroke
				(width 0)
				(type default)
			)
			(fill no)
			(layer "F.CrtYd")
		)
		(fp_poly
			(pts
				(xy -1.0922 -2.3114) (xy 1.0922 -2.3114) (xy 1.0922 2.3114) (xy -1.0922 2.3114)
			)
			(stroke
				(width 0)
				(type default)
			)
			(fill no)
			(layer "F.Fab")
		)
		(pad "1" smd rect
			(at 0 -1.397 90)
			(size 1.651 1.27)
			(layers "F.Cu" "F.Mask" "F.Paste")
			(net "P12V_HDD26")
		)
		(pad "2" smd rect
			(at 0 1.397 90)
			(size 1.651 1.27)
			(layers "F.Cu" "F.Mask" "F.Paste")
			(net "12V_PRE_26")
		)
	)
	(footprint ""
		(layer "F.Cu")
		(at 239.268 -382.1938)
		(property "Reference" "R1176"
			(at 0 0 0)
			(layer "F.SilkS")
			(hide yes)
			(effects
				(font
					(size 1.27 1.27)
				)
			)
		)
		(property "Value" "1KR2F-3-GP"
			(at 0.064008 -3.993896 0)
			(unlocked yes)
			(layer "F.Fab")
			(hide yes)
			(effects
				(font
					(size 1.016 1.016)
					(thickness 0.1524)
				)
			)
		)
		(property "Device Type" "R402H16"
			(at 0.064008 -5.517896 0)
			(unlocked yes)
			(layer "F.Fab")
			(hide yes)
			(effects
				(font
					(size 1.016 1.016)
					(thickness 0.1524)
				)
			)
		)
		(duplicate_pad_numbers_are_jumpers no)
		(fp_line
			(start -0.508 -0.9398)
			(end -0.508 0.9398)
			(stroke
				(width 0.1524)
				(type default)
			)
			(layer "F.SilkS")
		)
		(fp_line
			(start 0.508 -0.9398)
			(end -0.508 -0.9398)
			(stroke
				(width 0.1524)
				(type default)
			)
			(layer "F.SilkS")
		)
		(fp_rect
			(start -0.508 0.9398)
			(end 0.508 -0.9398)
			(stroke
				(width 0)
				(type default)
			)
			(fill no)
			(layer "F.CrtYd")
		)
		(fp_rect
			(start -0.508 0.9398)
			(end 0.508 -0.9398)
			(stroke
				(width 0)
				(type default)
			)
			(fill no)
			(layer "F.Fab")
		)
		(pad "1" smd custom
			(at 0 -0.4445)
			(size 0.1397 0.1397)
			(layers "F.Cu" "F.Mask" "F.Paste")
			(net "MB3_CM_VOUT_R")
			(options
				(clearance outline)
				(anchor circle)
			)
			(primitives
				(gr_poly
					(pts
						(arc
							(start -0.1778 -0.2794)
							(mid -0.249642 -0.249642)
							(end -0.2794 -0.1778)
						)
						(arc
							(start -0.2794 0.1778)
							(mid -0.249642 0.249642)
							(end -0.1778 0.2794)
						)
						(arc
							(start 0.1778 0.2794)
							(mid 0.249642 0.249642)
							(end 0.2794 0.1778)
						)
						(arc
							(start 0.2794 -0.1778)
							(mid 0.249642 -0.249642)
							(end 0.1778 -0.2794)
						)
					)
					(width 0)
					(fill yes)
				)
			)
		)
		(pad "2" smd custom
			(at 0 0.4445)
			(size 0.1397 0.1397)
			(layers "F.Cu" "F.Mask" "F.Paste")
			(net "P12V_A")
			(options
				(clearance outline)
				(anchor circle)
			)
			(primitives
				(gr_poly
					(pts
						(arc
							(start -0.1778 -0.2794)
							(mid -0.249642 -0.249642)
							(end -0.2794 -0.1778)
						)
						(arc
							(start -0.2794 0.1778)
							(mid -0.249642 0.249642)
							(end -0.1778 0.2794)
						)
						(arc
							(start 0.1778 0.2794)
							(mid 0.249642 0.249642)
							(end 0.2794 0.1778)
						)
						(arc
							(start 0.2794 -0.1778)
							(mid 0.249642 -0.249642)
							(end 0.1778 -0.2794)
						)
					)
					(width 0)
					(fill yes)
				)
			)
		)
	)
	(footprint ""
		(layer "F.Cu")
		(at 144.700498 -160.633918)
		(property "Reference" "R515"
			(at 0 0 0)
			(layer "F.SilkS")
			(hide yes)
			(effects
				(font
					(size 1.27 1.27)
				)
			)
		)
		(property "Value" "0R2J-2-GP"
			(at 0.064008 -3.993896 0)
			(unlocked yes)
			(layer "F.Fab")
			(hide yes)
			(effects
				(font
					(size 1.016 1.016)
					(thickness 0.1524)
				)
			)
		)
		(property "Device Type" "R402H16"
			(at 0.064008 -5.517896 0)
			(unlocked yes)
			(layer "F.Fab")
			(hide yes)
			(effects
				(font
					(size 1.016 1.016)
					(thickness 0.1524)
				)
			)
		)
		(duplicate_pad_numbers_are_jumpers no)
		(fp_line
			(start -0.508 -0.9398)
			(end -0.508 0.9398)
			(stroke
				(width 0.1524)
				(type default)
			)
			(layer "F.SilkS")
		)
		(fp_line
			(start 0.508 -0.9398)
			(end -0.508 -0.9398)
			(stroke
				(width 0.1524)
				(type default)
			)
			(layer "F.SilkS")
		)
		(fp_rect
			(start -0.508 0.9398)
			(end 0.508 -0.9398)
			(stroke
				(width 0)
				(type default)
			)
			(fill no)
			(layer "F.CrtYd")
		)
		(fp_rect
			(start -0.508 0.9398)
			(end 0.508 -0.9398)
			(stroke
				(width 0)
				(type default)
			)
			(fill no)
			(layer "F.Fab")
		)
		(pad "1" smd custom
			(at 0 -0.4445)
			(size 0.1397 0.1397)
			(layers "F.Cu" "F.Mask" "F.Paste")
			(net "SW_HDD_G16")
			(options
				(clearance outline)
				(anchor circle)
			)
			(primitives
				(gr_poly
					(pts
						(arc
							(start -0.1778 -0.2794)
							(mid -0.249642 -0.249642)
							(end -0.2794 -0.1778)
						)
						(arc
							(start -0.2794 0.1778)
							(mid -0.249642 0.249642)
							(end -0.1778 0.2794)
						)
						(arc
							(start 0.1778 0.2794)
							(mid 0.249642 0.249642)
							(end 0.2794 0.1778)
						)
						(arc
							(start 0.2794 -0.1778)
							(mid 0.249642 -0.249642)
							(end 0.1778 -0.2794)
						)
					)
					(width 0)
					(fill yes)
				)
			)
		)
		(pad "2" smd custom
			(at 0 0.4445)
			(size 0.1397 0.1397)
			(layers "F.Cu" "F.Mask" "F.Paste")
			(net "SW_HDD_R16")
			(options
				(clearance outline)
				(anchor circle)
			)
			(primitives
				(gr_poly
					(pts
						(arc
							(start -0.1778 -0.2794)
							(mid -0.249642 -0.249642)
							(end -0.2794 -0.1778)
						)
						(arc
							(start -0.2794 0.1778)
							(mid -0.249642 0.249642)
							(end -0.1778 0.2794)
						)
						(arc
							(start 0.1778 0.2794)
							(mid 0.249642 0.249642)
							(end 0.2794 0.1778)
						)
						(arc
							(start 0.2794 -0.1778)
							(mid 0.249642 -0.249642)
							(end 0.1778 -0.2794)
						)
					)
					(width 0)
					(fill yes)
				)
			)
		)
	)
	(footprint ""
		(layer "F.Cu")
		(at 398.88795 -42.585894 180)
		(property "Reference" "R876"
			(at 0 0 180)
			(layer "F.SilkS")
			(hide yes)
			(effects
				(font
					(size 1.27 1.27)
				)
			)
		)
		(property "Value" "0R2J-2-GP"
			(at 0.064008 -3.993896 180)
			(unlocked yes)
			(layer "F.Fab")
			(hide yes)
			(effects
				(font
					(size 1.016 1.016)
					(thickness 0.1524)
				)
			)
		)
		(property "Device Type" "R402H16"
			(at 0.064008 -5.517896 180)
			(unlocked yes)
			(layer "F.Fab")
			(hide yes)
			(effects
				(font
					(size 1.016 1.016)
					(thickness 0.1524)
				)
			)
		)
		(duplicate_pad_numbers_are_jumpers no)
		(fp_line
			(start 0.508 -0.9398)
			(end -0.508 -0.9398)
			(stroke
				(width 0.1524)
				(type default)
			)
			(layer "F.SilkS")
		)
		(fp_line
			(start -0.508 -0.9398)
			(end -0.508 0.9398)
			(stroke
				(width 0.1524)
				(type default)
			)
			(layer "F.SilkS")
		)
		(fp_rect
			(start -0.508 0.9398)
			(end 0.508 -0.9398)
			(stroke
				(width 0)
				(type default)
			)
			(fill no)
			(layer "F.CrtYd")
		)
		(fp_rect
			(start -0.508 0.9398)
			(end 0.508 -0.9398)
			(stroke
				(width 0)
				(type default)
			)
			(fill no)
			(layer "F.Fab")
		)
		(pad "1" smd custom
			(at 0 -0.4445 180)
			(size 0.1397 0.1397)
			(layers "F.Cu" "F.Mask" "F.Paste")
			(net "DRIVE_A_32_PWR")
			(options
				(clearance outline)
				(anchor circle)
			)
			(primitives
				(gr_poly
					(pts
						(arc
							(start -0.1778 -0.2794)
							(mid -0.249642 -0.249642)
							(end -0.2794 -0.1778)
						)
						(arc
							(start -0.2794 0.1778)
							(mid -0.249642 0.249642)
							(end -0.1778 0.2794)
						)
						(arc
							(start 0.1778 0.2794)
							(mid 0.249642 0.249642)
							(end 0.2794 0.1778)
						)
						(arc
							(start 0.2794 -0.1778)
							(mid 0.249642 -0.249642)
							(end 0.1778 -0.2794)
						)
					)
					(width 0)
					(fill yes)
				)
			)
		)
		(pad "2" smd custom
			(at 0 0.4445 180)
			(size 0.1397 0.1397)
			(layers "F.Cu" "F.Mask" "F.Paste")
			(net "SW_PWR_R_HDD32")
			(options
				(clearance outline)
				(anchor circle)
			)
			(primitives
				(gr_poly
					(pts
						(arc
							(start -0.1778 -0.2794)
							(mid -0.249642 -0.249642)
							(end -0.2794 -0.1778)
						)
						(arc
							(start -0.2794 0.1778)
							(mid -0.249642 0.249642)
							(end -0.1778 0.2794)
						)
						(arc
							(start 0.1778 0.2794)
							(mid 0.249642 0.249642)
							(end 0.2794 0.1778)
						)
						(arc
							(start 0.2794 -0.1778)
							(mid 0.249642 -0.249642)
							(end 0.1778 -0.2794)
						)
					)
					(width 0)
					(fill yes)
				)
			)
		)
	)
	(footprint ""
		(layer "F.Cu")
		(at 260.84149 -230.785162 -90)
		(property "Reference" "R95"
			(at 0 0 270)
			(layer "F.SilkS")
			(hide yes)
			(effects
				(font
					(size 1.27 1.27)
				)
			)
		)
		(property "Value" "0R2J-2-GP"
			(at 0.064008 -3.993896 270)
			(unlocked yes)
			(layer "F.Fab")
			(hide yes)
			(effects
				(font
					(size 1.016 1.016)
					(thickness 0.1524)
				)
			)
		)
		(property "Device Type" "R402H16"
			(at 0.064008 -5.517896 270)
			(unlocked yes)
			(layer "F.Fab")
			(hide yes)
			(effects
				(font
					(size 1.016 1.016)
					(thickness 0.1524)
				)
			)
		)
		(duplicate_pad_numbers_are_jumpers no)
		(fp_line
			(start -0.508 -0.9398)
			(end -0.508 0.9398)
			(stroke
				(width 0.1524)
				(type default)
			)
			(layer "F.SilkS")
		)
		(fp_line
			(start 0.508 -0.9398)
			(end -0.508 -0.9398)
			(stroke
				(width 0.1524)
				(type default)
			)
			(layer "F.SilkS")
		)
		(fp_rect
			(start -0.508 0.9398)
			(end 0.508 -0.9398)
			(stroke
				(width 0)
				(type default)
			)
			(fill no)
			(layer "F.CrtYd")
		)
		(fp_rect
			(start -0.508 0.9398)
			(end 0.508 -0.9398)
			(stroke
				(width 0)
				(type default)
			)
			(fill no)
			(layer "F.Fab")
		)
		(pad "1" smd custom
			(at 0 -0.4445 270)
			(size 0.1397 0.1397)
			(layers "F.Cu" "F.Mask" "F.Paste")
			(net "IO_EXP3_SDA")
			(options
				(clearance outline)
				(anchor circle)
			)
			(primitives
				(gr_poly
					(pts
						(arc
							(start -0.1778 -0.2794)
							(mid -0.249642 -0.249642)
							(end -0.2794 -0.1778)
						)
						(arc
							(start -0.2794 0.1778)
							(mid -0.249642 0.249642)
							(end -0.1778 0.2794)
						)
						(arc
							(start 0.1778 0.2794)
							(mid 0.249642 0.249642)
							(end 0.2794 0.1778)
						)
						(arc
							(start 0.2794 -0.1778)
							(mid 0.249642 -0.249642)
							(end 0.1778 -0.2794)
						)
					)
					(width 0)
					(fill yes)
				)
			)
		)
		(pad "2" smd custom
			(at 0 0.4445 270)
			(size 0.1397 0.1397)
			(layers "F.Cu" "F.Mask" "F.Paste")
			(net "I2C_DRIVE_A_PWR_SDA")
			(options
				(clearance outline)
				(anchor circle)
			)
			(primitives
				(gr_poly
					(pts
						(arc
							(start -0.1778 -0.2794)
							(mid -0.249642 -0.249642)
							(end -0.2794 -0.1778)
						)
						(arc
							(start -0.2794 0.1778)
							(mid -0.249642 0.249642)
							(end -0.1778 0.2794)
						)
						(arc
							(start 0.1778 0.2794)
							(mid 0.249642 0.249642)
							(end 0.2794 0.1778)
						)
						(arc
							(start 0.2794 -0.1778)
							(mid 0.249642 -0.249642)
							(end 0.1778 -0.2794)
						)
					)
					(width 0)
					(fill yes)
				)
			)
		)
	)
)
